(kicad_pcb
	(version 20260206)
	(generator "pcbnew")
	(generator_version "10.0")
	(general
		(thickness 1.6)
		(legacy_teardrops no)
	)
	(paper "A4")
	(title_block
		(title "04192023_DAF0TMB3IC0_F0TG_MB_C_brd_V02_OCP.brd")
		(comment 1 "Grand Teton / footprints 673-678 of 8354")
	)
	(layers
		(0 "F.Cu" signal "TOP")
		(4 "In1.Cu" signal "GND")
		(6 "In2.Cu" signal "IN1")
		(8 "In3.Cu" signal "GND1")
		(10 "In4.Cu" signal "IN2")
		(12 "In5.Cu" signal "GND2")
		(14 "In6.Cu" signal "IN3")
		(16 "In7.Cu" signal "GND3")
		(18 "In8.Cu" signal "VCC")
		(20 "In9.Cu" signal "VCC1")
		(22 "In10.Cu" signal "GND4")
		(24 "In11.Cu" signal "IN4")
		(26 "In12.Cu" signal "GND5")
		(28 "In13.Cu" signal "IN5")
		(30 "In14.Cu" signal "GND6")
		(32 "In15.Cu" signal "IN6")
		(34 "In16.Cu" signal "GND7")
		(2 "B.Cu" signal "BOTTOM")
		(9 "F.Adhes" user "F.Adhesive")
		(11 "B.Adhes" user "B.Adhesive")
		(13 "F.Paste" user "Package Geometry/Pastemask Top")
		(15 "B.Paste" user "Package Geometry/Pastemask Bottom")
		(5 "F.SilkS" user "Ref Des/Silkscreen Top")
		(7 "B.SilkS" user "Ref Des/Silkscreen Bottom")
		(1 "F.Mask" user "Board Geometry/Soldermask Top")
		(3 "B.Mask" user "Board Geometry/Soldermask Bottom")
		(17 "Dwgs.User" user "User.Drawings")
		(19 "Cmts.User" user "User.Comments")
		(21 "Eco1.User" user "User.Eco1")
		(23 "Eco2.User" user "User.Eco2")
		(25 "Edge.Cuts" user "Board Geometry/Outline")
		(27 "Margin" user)
		(31 "F.CrtYd" user "Package Geometry/Place Bound Top")
		(29 "B.CrtYd" user "Package Geometry/Place Bound Bottom")
		(35 "F.Fab" user "Ref Des/Assembly Top")
		(33 "B.Fab" user "Ref Des/Assembly Bottom")
	)
	(footprint ""
		(layer "F.Cu")
		(at 367.996978 -177.773076 90)
		(property "Reference" "PC477_C0P0_1"
			(at 0 0 90)
			(layer "F.SilkS")
			(hide yes)
			(effects
				(font
					(size 1.27 1.27)
				)
			)
		)
		(property "Value" ""
			(at 0 0 90)
			(layer "F.Fab")
			(effects
				(font
					(size 1.27 1.27)
				)
			)
		)
		(duplicate_pad_numbers_are_jumpers no)
		(fp_line
			(start 0.7874 -0.4064)
			(end 0.7874 0.4064)
			(stroke
				(width 0.1524)
				(type default)
			)
			(layer "F.SilkS")
		)
		(fp_line
			(start -0.7874 -0.4064)
			(end 0.7874 -0.4064)
			(stroke
				(width 0.1524)
				(type default)
			)
			(layer "F.SilkS")
		)
		(fp_line
			(start 0.7874 0.4064)
			(end -0.7874 0.4064)
			(stroke
				(width 0.1524)
				(type default)
			)
			(layer "F.SilkS")
		)
		(fp_line
			(start -0.7874 0.4064)
			(end -0.7874 -0.4064)
			(stroke
				(width 0.1524)
				(type default)
			)
			(layer "F.SilkS")
		)
		(fp_line
			(start -0.12065 -0.305054)
			(end -0.12065 -0.2794)
			(stroke
				(width 0.1)
				(type default)
			)
			(layer "F.Fab")
		)
		(fp_line
			(start -0.67945 -0.305054)
			(end -0.12065 -0.305054)
			(stroke
				(width 0.1)
				(type default)
			)
			(layer "F.Fab")
		)
		(fp_line
			(start 0.67945 -0.3048)
			(end 0.67945 0.3048)
			(stroke
				(width 0.1)
				(type default)
			)
			(layer "F.Fab")
		)
		(fp_line
			(start 0.12065 -0.3048)
			(end 0.67945 -0.3048)
			(stroke
				(width 0.1)
				(type default)
			)
			(layer "F.Fab")
		)
		(fp_line
			(start 0.12065 -0.2794)
			(end 0.12065 -0.3048)
			(stroke
				(width 0.1)
				(type default)
			)
			(layer "F.Fab")
		)
		(fp_line
			(start -0.12065 -0.2794)
			(end 0.12065 -0.2794)
			(stroke
				(width 0.1)
				(type default)
			)
			(layer "F.Fab")
		)
		(fp_line
			(start 0.120396 0.2794)
			(end -0.12065 0.2794)
			(stroke
				(width 0.1)
				(type default)
			)
			(layer "F.Fab")
		)
		(fp_line
			(start -0.12065 0.2794)
			(end -0.12065 0.3048)
			(stroke
				(width 0.1)
				(type default)
			)
			(layer "F.Fab")
		)
		(fp_line
			(start 0.67945 0.3048)
			(end 0.120396 0.3048)
			(stroke
				(width 0.1)
				(type default)
			)
			(layer "F.Fab")
		)
		(fp_line
			(start 0.120396 0.3048)
			(end 0.120396 0.2794)
			(stroke
				(width 0.1)
				(type default)
			)
			(layer "F.Fab")
		)
		(fp_line
			(start -0.12065 0.3048)
			(end -0.67945 0.3048)
			(stroke
				(width 0.1)
				(type default)
			)
			(layer "F.Fab")
		)
		(fp_line
			(start -0.67945 0.3048)
			(end -0.67945 -0.305054)
			(stroke
				(width 0.1)
				(type default)
			)
			(layer "F.Fab")
		)
		(pad "1" smd circle
			(at -0.40005 0 90)
			(size 0 0)
			(layers "F.Cu" "F.Mask" "F.Paste")
			(net "PVDDCR_CPU0_P0_PVCC")
		)
		(pad "2" smd circle
			(at 0.40005 0 90)
			(size 0 0)
			(layers "F.Cu" "F.Mask" "F.Paste")
			(net "GND")
		)
	)
	(footprint ""
		(layer "F.Cu")
		(at 184.023 -129.377948 -90)
		(property "Reference" "R215"
			(at 0 0 270)
			(layer "F.SilkS")
			(hide yes)
			(effects
				(font
					(size 1.27 1.27)
				)
			)
		)
		(property "Value" ""
			(at 0 0 270)
			(layer "F.Fab")
			(effects
				(font
					(size 1.27 1.27)
				)
			)
		)
		(duplicate_pad_numbers_are_jumpers no)
		(fp_line
			(start -0.7874 0.4064)
			(end -0.7874 -0.4064)
			(stroke
				(width 0.1524)
				(type default)
			)
			(layer "F.SilkS")
		)
		(fp_line
			(start 0.7874 0.4064)
			(end -0.7874 0.4064)
			(stroke
				(width 0.1524)
				(type default)
			)
			(layer "F.SilkS")
		)
		(fp_line
			(start -0.7874 -0.4064)
			(end 0.7874 -0.4064)
			(stroke
				(width 0.1524)
				(type default)
			)
			(layer "F.SilkS")
		)
		(fp_line
			(start 0.7874 -0.4064)
			(end 0.7874 0.4064)
			(stroke
				(width 0.1524)
				(type default)
			)
			(layer "F.SilkS")
		)
		(fp_line
			(start -0.67945 0.3048)
			(end -0.67945 -0.305054)
			(stroke
				(width 0.1)
				(type default)
			)
			(layer "F.Fab")
		)
		(fp_line
			(start -0.12065 0.3048)
			(end -0.67945 0.3048)
			(stroke
				(width 0.1)
				(type default)
			)
			(layer "F.Fab")
		)
		(fp_line
			(start 0.120396 0.3048)
			(end 0.120396 0.2794)
			(stroke
				(width 0.1)
				(type default)
			)
			(layer "F.Fab")
		)
		(fp_line
			(start 0.67945 0.3048)
			(end 0.120396 0.3048)
			(stroke
				(width 0.1)
				(type default)
			)
			(layer "F.Fab")
		)
		(fp_line
			(start -0.12065 0.2794)
			(end -0.12065 0.3048)
			(stroke
				(width 0.1)
				(type default)
			)
			(layer "F.Fab")
		)
		(fp_line
			(start 0.120396 0.2794)
			(end -0.12065 0.2794)
			(stroke
				(width 0.1)
				(type default)
			)
			(layer "F.Fab")
		)
		(fp_line
			(start -0.12065 -0.2794)
			(end 0.12065 -0.2794)
			(stroke
				(width 0.1)
				(type default)
			)
			(layer "F.Fab")
		)
		(fp_line
			(start 0.12065 -0.2794)
			(end 0.12065 -0.3048)
			(stroke
				(width 0.1)
				(type default)
			)
			(layer "F.Fab")
		)
		(fp_line
			(start 0.12065 -0.3048)
			(end 0.67945 -0.3048)
			(stroke
				(width 0.1)
				(type default)
			)
			(layer "F.Fab")
		)
		(fp_line
			(start 0.67945 -0.3048)
			(end 0.67945 0.3048)
			(stroke
				(width 0.1)
				(type default)
			)
			(layer "F.Fab")
		)
		(fp_line
			(start -0.67945 -0.305054)
			(end -0.12065 -0.305054)
			(stroke
				(width 0.1)
				(type default)
			)
			(layer "F.Fab")
		)
		(fp_line
			(start -0.12065 -0.305054)
			(end -0.12065 -0.2794)
			(stroke
				(width 0.1)
				(type default)
			)
			(layer "F.Fab")
		)
		(pad "1" smd circle
			(at -0.40005 0 270)
			(size 0 0)
			(layers "F.Cu" "F.Mask" "F.Paste")
			(net "CPU0_PWR_BTN_N")
		)
		(pad "2" smd circle
			(at 0.40005 0 270)
			(size 0 0)
			(layers "F.Cu" "F.Mask" "F.Paste")
			(net "FM_CPU0_PWR_BTN_N")
		)
	)
	(footprint ""
		(layer "F.Cu")
		(at 152.329642 -73.589134 180)
		(property "Reference" "PC6021"
			(at 0 0 180)
			(layer "F.SilkS")
			(hide yes)
			(effects
				(font
					(size 1.27 1.27)
				)
			)
		)
		(property "Value" ""
			(at 0 0 180)
			(layer "F.Fab")
			(effects
				(font
					(size 1.27 1.27)
				)
			)
		)
		(duplicate_pad_numbers_are_jumpers no)
		(fp_line
			(start 0.7874 0.4064)
			(end -0.7874 0.4064)
			(stroke
				(width 0.1524)
				(type default)
			)
			(layer "F.SilkS")
		)
		(fp_line
			(start 0.7874 -0.4064)
			(end 0.7874 0.4064)
			(stroke
				(width 0.1524)
				(type default)
			)
			(layer "F.SilkS")
		)
		(fp_line
			(start -0.7874 0.4064)
			(end -0.7874 -0.4064)
			(stroke
				(width 0.1524)
				(type default)
			)
			(layer "F.SilkS")
		)
		(fp_line
			(start -0.7874 -0.4064)
			(end 0.7874 -0.4064)
			(stroke
				(width 0.1524)
				(type default)
			)
			(layer "F.SilkS")
		)
		(fp_line
			(start 0.67945 0.3048)
			(end 0.120396 0.3048)
			(stroke
				(width 0.1)
				(type default)
			)
			(layer "F.Fab")
		)
		(fp_line
			(start 0.67945 -0.3048)
			(end 0.67945 0.3048)
			(stroke
				(width 0.1)
				(type default)
			)
			(layer "F.Fab")
		)
		(fp_line
			(start 0.12065 -0.2794)
			(end 0.12065 -0.3048)
			(stroke
				(width 0.1)
				(type default)
			)
			(layer "F.Fab")
		)
		(fp_line
			(start 0.12065 -0.3048)
			(end 0.67945 -0.3048)
			(stroke
				(width 0.1)
				(type default)
			)
			(layer "F.Fab")
		)
		(fp_line
			(start 0.120396 0.3048)
			(end 0.120396 0.2794)
			(stroke
				(width 0.1)
				(type default)
			)
			(layer "F.Fab")
		)
		(fp_line
			(start 0.120396 0.2794)
			(end -0.12065 0.2794)
			(stroke
				(width 0.1)
				(type default)
			)
			(layer "F.Fab")
		)
		(fp_line
			(start -0.12065 0.3048)
			(end -0.67945 0.3048)
			(stroke
				(width 0.1)
				(type default)
			)
			(layer "F.Fab")
		)
		(fp_line
			(start -0.12065 0.2794)
			(end -0.12065 0.3048)
			(stroke
				(width 0.1)
				(type default)
			)
			(layer "F.Fab")
		)
		(fp_line
			(start -0.12065 -0.2794)
			(end 0.12065 -0.2794)
			(stroke
				(width 0.1)
				(type default)
			)
			(layer "F.Fab")
		)
		(fp_line
			(start -0.12065 -0.305054)
			(end -0.12065 -0.2794)
			(stroke
				(width 0.1)
				(type default)
			)
			(layer "F.Fab")
		)
		(fp_line
			(start -0.67945 0.3048)
			(end -0.67945 -0.305054)
			(stroke
				(width 0.1)
				(type default)
			)
			(layer "F.Fab")
		)
		(fp_line
			(start -0.67945 -0.305054)
			(end -0.12065 -0.305054)
			(stroke
				(width 0.1)
				(type default)
			)
			(layer "F.Fab")
		)
		(pad "1" smd circle
			(at -0.40005 0 180)
			(size 0 0)
			(layers "F.Cu" "F.Mask" "F.Paste")
			(net "P1V8_AUX")
		)
		(pad "2" smd circle
			(at 0.40005 0 180)
			(size 0 0)
			(layers "F.Cu" "F.Mask" "F.Paste")
			(net "GND")
		)
	)
	(footprint ""
		(layer "F.Cu")
		(at 463.462624 -98.564954 180)
		(property "Reference" "R1289"
			(at 0 0 180)
			(layer "F.SilkS")
			(hide yes)
			(effects
				(font
					(size 1.27 1.27)
				)
			)
		)
		(property "Value" ""
			(at 0 0 180)
			(layer "F.Fab")
			(effects
				(font
					(size 1.27 1.27)
				)
			)
		)
		(duplicate_pad_numbers_are_jumpers no)
		(fp_line
			(start 0.7874 0.4064)
			(end -0.7874 0.4064)
			(stroke
				(width 0.1524)
				(type default)
			)
			(layer "F.SilkS")
		)
		(fp_line
			(start 0.7874 -0.4064)
			(end 0.7874 0.4064)
			(stroke
				(width 0.1524)
				(type default)
			)
			(layer "F.SilkS")
		)
		(fp_line
			(start -0.7874 0.4064)
			(end -0.7874 -0.4064)
			(stroke
				(width 0.1524)
				(type default)
			)
			(layer "F.SilkS")
		)
		(fp_line
			(start -0.7874 -0.4064)
			(end 0.7874 -0.4064)
			(stroke
				(width 0.1524)
				(type default)
			)
			(layer "F.SilkS")
		)
		(fp_line
			(start 0.67945 0.3048)
			(end 0.120396 0.3048)
			(stroke
				(width 0.1)
				(type default)
			)
			(layer "F.Fab")
		)
		(fp_line
			(start 0.67945 -0.3048)
			(end 0.67945 0.3048)
			(stroke
				(width 0.1)
				(type default)
			)
			(layer "F.Fab")
		)
		(fp_line
			(start 0.12065 -0.2794)
			(end 0.12065 -0.3048)
			(stroke
				(width 0.1)
				(type default)
			)
			(layer "F.Fab")
		)
		(fp_line
			(start 0.12065 -0.3048)
			(end 0.67945 -0.3048)
			(stroke
				(width 0.1)
				(type default)
			)
			(layer "F.Fab")
		)
		(fp_line
			(start 0.120396 0.3048)
			(end 0.120396 0.2794)
			(stroke
				(width 0.1)
				(type default)
			)
			(layer "F.Fab")
		)
		(fp_line
			(start 0.120396 0.2794)
			(end -0.12065 0.2794)
			(stroke
				(width 0.1)
				(type default)
			)
			(layer "F.Fab")
		)
		(fp_line
			(start -0.12065 0.3048)
			(end -0.67945 0.3048)
			(stroke
				(width 0.1)
				(type default)
			)
			(layer "F.Fab")
		)
		(fp_line
			(start -0.12065 0.2794)
			(end -0.12065 0.3048)
			(stroke
				(width 0.1)
				(type default)
			)
			(layer "F.Fab")
		)
		(fp_line
			(start -0.12065 -0.2794)
			(end 0.12065 -0.2794)
			(stroke
				(width 0.1)
				(type default)
			)
			(layer "F.Fab")
		)
		(fp_line
			(start -0.12065 -0.305054)
			(end -0.12065 -0.2794)
			(stroke
				(width 0.1)
				(type default)
			)
			(layer "F.Fab")
		)
		(fp_line
			(start -0.67945 0.3048)
			(end -0.67945 -0.305054)
			(stroke
				(width 0.1)
				(type default)
			)
			(layer "F.Fab")
		)
		(fp_line
			(start -0.67945 -0.305054)
			(end -0.12065 -0.305054)
			(stroke
				(width 0.1)
				(type default)
			)
			(layer "F.Fab")
		)
		(pad "1" smd circle
			(at -0.40005 0 180)
			(size 0 0)
			(layers "F.Cu" "F.Mask" "F.Paste")
			(net "FB_BMC_ISOLATE")
		)
		(pad "2" smd circle
			(at 0.40005 0 180)
			(size 0 0)
			(layers "F.Cu" "F.Mask" "F.Paste")
			(net "GND")
		)
	)
	(footprint ""
		(layer "F.Cu")
		(at 370.905278 -143.504158)
		(property "Reference" "C5018"
			(at 0 0 0)
			(layer "F.SilkS")
			(hide yes)
			(effects
				(font
					(size 1.27 1.27)
				)
			)
		)
		(property "Value" ""
			(at 0 0 0)
			(layer "F.Fab")
			(effects
				(font
					(size 1.27 1.27)
				)
			)
		)
		(duplicate_pad_numbers_are_jumpers no)
		(fp_line
			(start -0.7874 -0.4064)
			(end 0.7874 -0.4064)
			(stroke
				(width 0.1524)
				(type default)
			)
			(layer "F.SilkS")
		)
		(fp_line
			(start -0.7874 0.4064)
			(end -0.7874 -0.4064)
			(stroke
				(width 0.1524)
				(type default)
			)
			(layer "F.SilkS")
		)
		(fp_line
			(start 0.7874 -0.4064)
			(end 0.7874 0.4064)
			(stroke
				(width 0.1524)
				(type default)
			)
			(layer "F.SilkS")
		)
		(fp_line
			(start 0.7874 0.4064)
			(end -0.7874 0.4064)
			(stroke
				(width 0.1524)
				(type default)
			)
			(layer "F.SilkS")
		)
		(fp_line
			(start -0.67945 -0.305054)
			(end -0.12065 -0.305054)
			(stroke
				(width 0.1)
				(type default)
			)
			(layer "F.Fab")
		)
		(fp_line
			(start -0.67945 0.3048)
			(end -0.67945 -0.305054)
			(stroke
				(width 0.1)
				(type default)
			)
			(layer "F.Fab")
		)
		(fp_line
			(start -0.12065 -0.305054)
			(end -0.12065 -0.2794)
			(stroke
				(width 0.1)
				(type default)
			)
			(layer "F.Fab")
		)
		(fp_line
			(start -0.12065 -0.2794)
			(end 0.12065 -0.2794)
			(stroke
				(width 0.1)
				(type default)
			)
			(layer "F.Fab")
		)
		(fp_line
			(start -0.12065 0.2794)
			(end -0.12065 0.3048)
			(stroke
				(width 0.1)
				(type default)
			)
			(layer "F.Fab")
		)
		(fp_line
			(start -0.12065 0.3048)
			(end -0.67945 0.3048)
			(stroke
				(width 0.1)
				(type default)
			)
			(layer "F.Fab")
		)
		(fp_line
			(start 0.120396 0.2794)
			(end -0.12065 0.2794)
			(stroke
				(width 0.1)
				(type default)
			)
			(layer "F.Fab")
		)
		(fp_line
			(start 0.120396 0.3048)
			(end 0.120396 0.2794)
			(stroke
				(width 0.1)
				(type default)
			)
			(layer "F.Fab")
		)
		(fp_line
			(start 0.12065 -0.3048)
			(end 0.67945 -0.3048)
			(stroke
				(width 0.1)
				(type default)
			)
			(layer "F.Fab")
		)
		(fp_line
			(start 0.12065 -0.2794)
			(end 0.12065 -0.3048)
			(stroke
				(width 0.1)
				(type default)
			)
			(layer "F.Fab")
		)
		(fp_line
			(start 0.67945 -0.3048)
			(end 0.67945 0.3048)
			(stroke
				(width 0.1)
				(type default)
			)
			(layer "F.Fab")
		)
		(fp_line
			(start 0.67945 0.3048)
			(end 0.120396 0.3048)
			(stroke
				(width 0.1)
				(type default)
			)
			(layer "F.Fab")
		)
		(pad "1" smd circle
			(at -0.40005 0)
			(size 0 0)
			(layers "F.Cu" "F.Mask" "F.Paste")
			(net "GND")
		)
		(pad "2" smd circle
			(at 0.40005 0)
			(size 0 0)
			(layers "F.Cu" "F.Mask" "F.Paste")
			(net "PWRGD_PVDDCR_SOC_P0")
		)
	)
	(footprint ""
		(layer "F.Cu")
		(at 365.835692 -261.255002 180)
		(property "Reference" "C2555"
			(at 0 0 180)
			(layer "F.SilkS")
			(hide yes)
			(effects
				(font
					(size 1.27 1.27)
				)
			)
		)
		(property "Value" ""
			(at 0 0 180)
			(layer "F.Fab")
			(effects
				(font
					(size 1.27 1.27)
				)
			)
		)
		(duplicate_pad_numbers_are_jumpers no)
		(fp_line
			(start 0.7874 0.4064)
			(end -0.7874 0.4064)
			(stroke
				(width 0.1524)
				(type default)
			)
			(layer "F.SilkS")
		)
		(fp_line
			(start 0.7874 -0.4064)
			(end 0.7874 0.4064)
			(stroke
				(width 0.1524)
				(type default)
			)
			(layer "F.SilkS")
		)
		(fp_line
			(start -0.7874 0.4064)
			(end -0.7874 -0.4064)
			(stroke
				(width 0.1524)
				(type default)
			)
			(layer "F.SilkS")
		)
		(fp_line
			(start -0.7874 -0.4064)
			(end 0.7874 -0.4064)
			(stroke
				(width 0.1524)
				(type default)
			)
			(layer "F.SilkS")
		)
		(fp_line
			(start 0.67945 0.3048)
			(end 0.120396 0.3048)
			(stroke
				(width 0.1)
				(type default)
			)
			(layer "F.Fab")
		)
		(fp_line
			(start 0.67945 -0.3048)
			(end 0.67945 0.3048)
			(stroke
				(width 0.1)
				(type default)
			)
			(layer "F.Fab")
		)
		(fp_line
			(start 0.12065 -0.2794)
			(end 0.12065 -0.3048)
			(stroke
				(width 0.1)
				(type default)
			)
			(layer "F.Fab")
		)
		(fp_line
			(start 0.12065 -0.3048)
			(end 0.67945 -0.3048)
			(stroke
				(width 0.1)
				(type default)
			)
			(layer "F.Fab")
		)
		(fp_line
			(start 0.120396 0.3048)
			(end 0.120396 0.2794)
			(stroke
				(width 0.1)
				(type default)
			)
			(layer "F.Fab")
		)
		(fp_line
			(start 0.120396 0.2794)
			(end -0.12065 0.2794)
			(stroke
				(width 0.1)
				(type default)
			)
			(layer "F.Fab")
		)
		(fp_line
			(start -0.12065 0.3048)
			(end -0.67945 0.3048)
			(stroke
				(width 0.1)
				(type default)
			)
			(layer "F.Fab")
		)
		(fp_line
			(start -0.12065 0.2794)
			(end -0.12065 0.3048)
			(stroke
				(width 0.1)
				(type default)
			)
			(layer "F.Fab")
		)
		(fp_line
			(start -0.12065 -0.2794)
			(end 0.12065 -0.2794)
			(stroke
				(width 0.1)
				(type default)
			)
			(layer "F.Fab")
		)
		(fp_line
			(start -0.12065 -0.305054)
			(end -0.12065 -0.2794)
			(stroke
				(width 0.1)
				(type default)
			)
			(layer "F.Fab")
		)
		(fp_line
			(start -0.67945 0.3048)
			(end -0.67945 -0.305054)
			(stroke
				(width 0.1)
				(type default)
			)
			(layer "F.Fab")
		)
		(fp_line
			(start -0.67945 -0.305054)
			(end -0.12065 -0.305054)
			(stroke
				(width 0.1)
				(type default)
			)
			(layer "F.Fab")
		)
		(pad "1" smd circle
			(at -0.40005 0 180)
			(size 0 0)
			(layers "F.Cu" "F.Mask" "F.Paste")
			(net "PVDDCR_SOC_P0")
		)
		(pad "2" smd circle
			(at 0.40005 0 180)
			(size 0 0)
			(layers "F.Cu" "F.Mask" "F.Paste")
			(net "GND")
		)
	)
)
